# S9S_MB_2U (Grand Teton) — schematic netlist excerpt (pin names and nets, part order shuffled) for the footprints in the layout excerpt that follows; sources: Cadence DE-HDL packaged netlist, KiCad conversion of 03242023_DA0F0TMBIJ0_F0T_Motherboard_J_brd_V01_OCP.brd

R3575  Q_RES  10 1% CHIP  pkg 0402LF  page 172 : A = P3V3_M2_0 ; B = VSENSE_P12V_INA230_4_INN
R3295  Q_RES  4.7K 1% CHIP  pkg 0402LF  page 190 : A = P3V3_M2_0 ; B = LED_HDD_ACTIVITY_N
C1535  Q_CAP_DIFFBUS  DIFF BUS_0.22UF 6.3V 20% X6S  pkg C0201  page 177 : \1\ = P5E_CPU1_PE3_TX_C_DP<6> ; \2\ = P5E_CPU1_PE3_TX_DP<6>

(kicad_pcb
	(version 20260206)
	(generator "pcbnew")
	(generator_version "10.0")
	(general
		(thickness 1.6)
		(legacy_teardrops no)
	)
	(paper "A4")
	(title_block
		(title "03242023_DA0F0TMBIJ0_F0T_Motherboard_J_brd_V01_OCP.brd")
		(comment 1 "Grand Teton / footprints 3352-3354 of 6105")
	)
	(layers
		(0 "F.Cu" signal "TOP")
		(4 "In1.Cu" signal "GND")
		(6 "In2.Cu" signal "IN1")
		(8 "In3.Cu" signal "GND1")
		(10 "In4.Cu" signal "IN2")
		(12 "In5.Cu" signal "GND2")
		(14 "In6.Cu" signal "IN3")
		(16 "In7.Cu" signal "GND3")
		(18 "In8.Cu" signal "VCC")
		(20 "In9.Cu" signal "VCC1")
		(22 "In10.Cu" signal "GND4")
		(24 "In11.Cu" signal "IN4")
		(26 "In12.Cu" signal "GND5")
		(28 "In13.Cu" signal "IN5")
		(30 "In14.Cu" signal "GND6")
		(32 "In15.Cu" signal "IN6")
		(34 "In16.Cu" signal "GND7")
		(2 "B.Cu" signal "BOTTOM")
		(9 "F.Adhes" user "F.Adhesive")
		(11 "B.Adhes" user "B.Adhesive")
		(13 "F.Paste" user "Package Geometry/Pastemask Top")
		(15 "B.Paste" user "Package Geometry/Pastemask Bottom")
		(5 "F.SilkS" user "Ref Des/Silkscreen Top")
		(7 "B.SilkS" user "Ref Des/Silkscreen Bottom")
		(1 "F.Mask" user "Board Geometry/Soldermask Top")
		(3 "B.Mask" user "Board Geometry/Soldermask Bottom")
		(17 "Dwgs.User" user "User.Drawings")
		(19 "Cmts.User" user "User.Comments")
		(21 "Eco1.User" user "User.Eco1")
		(23 "Eco2.User" user "User.Eco2")
		(25 "Edge.Cuts" user "Board Geometry/Outline")
		(27 "Margin" user)
		(31 "F.CrtYd" user "Package Geometry/Place Bound Top")
		(29 "B.CrtYd" user "Package Geometry/Place Bound Bottom")
		(35 "F.Fab" user "Ref Des/Assembly Top")
		(33 "B.Fab" user "Ref Des/Assembly Bottom")
	)
	(footprint ""
		(layer "F.Cu")
		(at 145.34388 -42.446448)
		(property "Reference" "R3295"
			(at 0 0 0)
			(layer "F.SilkS")
			(hide yes)
			(effects
				(font
					(size 1.27 1.27)
				)
			)
		)
		(property "Value" ""
			(at 0 0 0)
			(layer "F.Fab")
			(effects
				(font
					(size 1.27 1.27)
				)
			)
		)
		(duplicate_pad_numbers_are_jumpers no)
		(fp_line
			(start -0.7874 -0.4064)
			(end 0.7874 -0.4064)
			(stroke
				(width 0.1524)
				(type default)
			)
			(layer "F.SilkS")
		)
		(fp_line
			(start -0.7874 0.4064)
			(end -0.7874 -0.4064)
			(stroke
				(width 0.1524)
				(type default)
			)
			(layer "F.SilkS")
		)
		(fp_line
			(start 0.7874 -0.4064)
			(end 0.7874 0.4064)
			(stroke
				(width 0.1524)
				(type default)
			)
			(layer "F.SilkS")
		)
		(fp_line
			(start 0.7874 0.4064)
			(end -0.7874 0.4064)
			(stroke
				(width 0.1524)
				(type default)
			)
			(layer "F.SilkS")
		)
		(fp_line
			(start -0.67945 -0.305054)
			(end -0.12065 -0.305054)
			(stroke
				(width 0.1)
				(type default)
			)
			(layer "F.Fab")
		)
		(fp_line
			(start -0.67945 0.3048)
			(end -0.67945 -0.305054)
			(stroke
				(width 0.1)
				(type default)
			)
			(layer "F.Fab")
		)
		(fp_line
			(start -0.12065 -0.305054)
			(end -0.12065 -0.2794)
			(stroke
				(width 0.1)
				(type default)
			)
			(layer "F.Fab")
		)
		(fp_line
			(start -0.12065 -0.2794)
			(end 0.12065 -0.2794)
			(stroke
				(width 0.1)
				(type default)
			)
			(layer "F.Fab")
		)
		(fp_line
			(start -0.12065 0.2794)
			(end -0.12065 0.3048)
			(stroke
				(width 0.1)
				(type default)
			)
			(layer "F.Fab")
		)
		(fp_line
			(start -0.12065 0.3048)
			(end -0.67945 0.3048)
			(stroke
				(width 0.1)
				(type default)
			)
			(layer "F.Fab")
		)
		(fp_line
			(start 0.120396 0.2794)
			(end -0.12065 0.2794)
			(stroke
				(width 0.1)
				(type default)
			)
			(layer "F.Fab")
		)
		(fp_line
			(start 0.120396 0.3048)
			(end 0.120396 0.2794)
			(stroke
				(width 0.1)
				(type default)
			)
			(layer "F.Fab")
		)
		(fp_line
			(start 0.12065 -0.3048)
			(end 0.67945 -0.3048)
			(stroke
				(width 0.1)
				(type default)
			)
			(layer "F.Fab")
		)
		(fp_line
			(start 0.12065 -0.2794)
			(end 0.12065 -0.3048)
			(stroke
				(width 0.1)
				(type default)
			)
			(layer "F.Fab")
		)
		(fp_line
			(start 0.67945 -0.3048)
			(end 0.67945 0.3048)
			(stroke
				(width 0.1)
				(type default)
			)
			(layer "F.Fab")
		)
		(fp_line
			(start 0.67945 0.3048)
			(end 0.120396 0.3048)
			(stroke
				(width 0.1)
				(type default)
			)
			(layer "F.Fab")
		)
		(pad "1" smd circle
			(at -0.40005 0)
			(size 0 0)
			(layers "F.Cu" "F.Mask" "F.Paste")
			(net "P3V3_M2_0")
		)
		(pad "2" smd circle
			(at 0.40005 0)
			(size 0 0)
			(layers "F.Cu" "F.Mask" "F.Paste")
			(net "LED_HDD_ACTIVITY_N")
		)
	)
	(footprint ""
		(layer "F.Cu")
		(at 149.959314 -408.517344 -90)
		(property "Reference" "C1535"
			(at 0 0 270)
			(layer "F.SilkS")
			(hide yes)
			(effects
				(font
					(size 1.27 1.27)
				)
			)
		)
		(property "Value" ""
			(at 0 0 270)
			(layer "F.Fab")
			(effects
				(font
					(size 1.27 1.27)
				)
			)
		)
		(duplicate_pad_numbers_are_jumpers no)
		(fp_line
			(start -0.299974 0.150114)
			(end -0.299974 -0.150114)
			(stroke
				(width 0.1)
				(type default)
			)
			(layer "F.Fab")
		)
		(fp_line
			(start 0.299974 0.150114)
			(end -0.299974 0.150114)
			(stroke
				(width 0.1)
				(type default)
			)
			(layer "F.Fab")
		)
		(fp_line
			(start -0.299974 -0.150114)
			(end 0.299974 -0.150114)
			(stroke
				(width 0.1)
				(type default)
			)
			(layer "F.Fab")
		)
		(fp_line
			(start 0.299974 -0.150114)
			(end 0.299974 0.150114)
			(stroke
				(width 0.1)
				(type default)
			)
			(layer "F.Fab")
		)
		(pad "1" smd rect
			(at -0.2667 0 270)
			(size 0.3048 0.381)
			(layers "F.Cu" "F.Mask" "F.Paste")
			(net "P5E_CPU1_PE3_TX_C_DP<6>")
		)
		(pad "2" smd rect
			(at 0.2667 0 270)
			(size 0.3048 0.381)
			(layers "F.Cu" "F.Mask" "F.Paste")
			(net "P5E_CPU1_PE3_TX_DP<6>")
		)
	)
	(footprint ""
		(layer "F.Cu")
		(at 159.267144 -52.851304 180)
		(property "Reference" "R3575"
			(at 0 0 180)
			(layer "F.SilkS")
			(hide yes)
			(effects
				(font
					(size 1.27 1.27)
				)
			)
		)
		(property "Value" ""
			(at 0 0 180)
			(layer "F.Fab")
			(effects
				(font
					(size 1.27 1.27)
				)
			)
		)
		(duplicate_pad_numbers_are_jumpers no)
		(fp_line
			(start 0.7874 0.4064)
			(end -0.7874 0.4064)
			(stroke
				(width 0.1524)
				(type default)
			)
			(layer "F.SilkS")
		)
		(fp_line
			(start 0.7874 -0.4064)
			(end 0.7874 0.4064)
			(stroke
				(width 0.1524)
				(type default)
			)
			(layer "F.SilkS")
		)
		(fp_line
			(start -0.7874 0.4064)
			(end -0.7874 -0.4064)
			(stroke
				(width 0.1524)
				(type default)
			)
			(layer "F.SilkS")
		)
		(fp_line
			(start -0.7874 -0.4064)
			(end 0.7874 -0.4064)
			(stroke
				(width 0.1524)
				(type default)
			)
			(layer "F.SilkS")
		)
		(fp_line
			(start 0.67945 0.3048)
			(end 0.120396 0.3048)
			(stroke
				(width 0.1)
				(type default)
			)
			(layer "F.Fab")
		)
		(fp_line
			(start 0.67945 -0.3048)
			(end 0.67945 0.3048)
			(stroke
				(width 0.1)
				(type default)
			)
			(layer "F.Fab")
		)
		(fp_line
			(start 0.12065 -0.2794)
			(end 0.12065 -0.3048)
			(stroke
				(width 0.1)
				(type default)
			)
			(layer "F.Fab")
		)
		(fp_line
			(start 0.12065 -0.3048)
			(end 0.67945 -0.3048)
			(stroke
				(width 0.1)
				(type default)
			)
			(layer "F.Fab")
		)
		(fp_line
			(start 0.120396 0.3048)
			(end 0.120396 0.2794)
			(stroke
				(width 0.1)
				(type default)
			)
			(layer "F.Fab")
		)
		(fp_line
			(start 0.120396 0.2794)
			(end -0.12065 0.2794)
			(stroke
				(width 0.1)
				(type default)
			)
			(layer "F.Fab")
		)
		(fp_line
			(start -0.12065 0.3048)
			(end -0.67945 0.3048)
			(stroke
				(width 0.1)
				(type default)
			)
			(layer "F.Fab")
		)
		(fp_line
			(start -0.12065 0.2794)
			(end -0.12065 0.3048)
			(stroke
				(width 0.1)
				(type default)
			)
			(layer "F.Fab")
		)
		(fp_line
			(start -0.12065 -0.2794)
			(end 0.12065 -0.2794)
			(stroke
				(width 0.1)
				(type default)
			)
			(layer "F.Fab")
		)
		(fp_line
			(start -0.12065 -0.305054)
			(end -0.12065 -0.2794)
			(stroke
				(width 0.1)
				(type default)
			)
			(layer "F.Fab")
		)
		(fp_line
			(start -0.67945 0.3048)
			(end -0.67945 -0.305054)
			(stroke
				(width 0.1)
				(type default)
			)
			(layer "F.Fab")
		)
		(fp_line
			(start -0.67945 -0.305054)
			(end -0.12065 -0.305054)
			(stroke
				(width 0.1)
				(type default)
			)
			(layer "F.Fab")
		)
		(pad "1" smd circle
			(at -0.40005 0 180)
			(size 0 0)
			(layers "F.Cu" "F.Mask" "F.Paste")
			(net "P3V3_M2_0")
		)
		(pad "2" smd circle
			(at 0.40005 0 180)
			(size 0 0)
			(layers "F.Cu" "F.Mask" "F.Paste")
			(net "VSENSE_P12V_INA230_4_INN")
		)
	)
)
